(kicad_pcb
	(version 20241229)
	(generator "pcbnew")
	(generator_version "9.0")
	(general
		(thickness 1.552)
		(legacy_teardrops no)
	)
	(paper "A4")
	(title_block
		(date "2023-07-25")
		(rev "1.1.4")
		(comment 9 "footprints 49-52 of 379")
	)
	(layers
		(0 "F.Cu" signal)
		(4 "In1.Cu" signal)
		(6 "In2.Cu" signal)
		(8 "In3.Cu" signal)
		(10 "In4.Cu" signal)
		(12 "In5.Cu" signal)
		(14 "In6.Cu" signal)
		(2 "B.Cu" signal)
		(9 "F.Adhes" user "F.Adhesive")
		(11 "B.Adhes" user "B.Adhesive")
		(13 "F.Paste" user)
		(15 "B.Paste" user)
		(5 "F.SilkS" user "F.Silkscreen")
		(7 "B.SilkS" user "B.Silkscreen")
		(1 "F.Mask" user)
		(3 "B.Mask" user)
		(17 "Dwgs.User" user "User.Drawings")
		(19 "Cmts.User" user "User.Comments")
		(21 "Eco1.User" user "User.Eco1")
		(23 "Eco2.User" user "User.Eco2")
		(25 "Edge.Cuts" user)
		(27 "Margin" user)
		(31 "F.CrtYd" user "F.Courtyard")
		(29 "B.CrtYd" user "B.Courtyard")
		(35 "F.Fab" user)
		(33 "B.Fab" user)
	)
	(footprint "antmicro-footprints:C_0402_1005Metric"
		(layer "F.Cu")
		(at 83.3 104.675 180)
		(descr "Capacitor SMD 0402")
		(tags "capacitor SMD 0402")
		(property "Reference" "C78"
			(at -4.13 7.835 0)
			(layer "F.SilkS")
			(effects
				(font
					(size 0.65 0.65)
					(thickness 0.15)
				)
				(justify right bottom)
			)
		)
		(property "Value" "C_4u7_0402"
			(at 0 1.4 0)
			(layer "F.Fab")
			(hide yes)
			(effects
				(font
					(size 0.7 0.7)
					(thickness 0.15)
				)
				(justify right bottom)
			)
		)
		(property "Datasheet" "https://www.murata.com/products/productdetail?partno=GRM155R61A475MEAA%23"
			(at 0 0 180)
			(layer "F.Fab")
			(hide yes)
			(effects
				(font
					(size 1.27 1.27)
					(thickness 0.15)
				)
			)
		)
		(property "Description" "SMD Multilayer Ceramic Capacitor, 4.7 µF, 10 V, 0402 [1005 Metric], ± 20%, X5R, GRM Series"
			(at 0 0 180)
			(layer "F.Fab")
			(hide yes)
			(effects
				(font
					(size 1.27 1.27)
					(thickness 0.15)
				)
			)
		)
		(property "Author" "Antmicro"
			(at 166.6 209.35 0)
			(layer "F.Fab")
			(hide yes)
			(effects
				(font
					(size 1 1)
					(thickness 0.15)
				)
			)
		)
		(property "Dielectric" ""
			(at 166.6 209.35 0)
			(layer "F.Fab")
			(hide yes)
			(effects
				(font
					(size 1 1)
					(thickness 0.15)
				)
			)
		)
		(property "License" "Apache-2.0"
			(at 166.6 209.35 0)
			(layer "F.Fab")
			(hide yes)
			(effects
				(font
					(size 1 1)
					(thickness 0.15)
				)
			)
		)
		(property "MPN" "GRM155R61A475MEAAD"
			(at 166.6 209.35 0)
			(layer "F.Fab")
			(hide yes)
			(effects
				(font
					(size 1 1)
					(thickness 0.15)
				)
			)
		)
		(property "Manufacturer" "Murata"
			(at 166.6 209.35 0)
			(layer "F.Fab")
			(hide yes)
			(effects
				(font
					(size 1 1)
					(thickness 0.15)
				)
			)
		)
		(property "Val" "4u7"
			(at 166.6 209.35 0)
			(layer "F.Fab")
			(hide yes)
			(effects
				(font
					(size 1 1)
					(thickness 0.15)
				)
			)
		)
		(property "Voltage" ""
			(at 166.6 209.35 0)
			(layer "F.Fab")
			(hide yes)
			(effects
				(font
					(size 1 1)
					(thickness 0.15)
				)
			)
		)
		(sheetname "/SDI/")
		(sheetfile "sdi.kicad_sch")
		(attr smd)
		(fp_rect
			(start -0.925 -0.47)
			(end 0.925 0.47)
			(stroke
				(width 0.05)
				(type default)
			)
			(fill no)
			(layer "F.CrtYd")
		)
		(fp_line
			(start 0.504 0.248)
			(end -0.494 0.248)
			(stroke
				(width 0.15)
				(type solid)
			)
			(layer "F.Fab")
		)
		(fp_line
			(start 0.504 -0.25)
			(end 0.504 0.248)
			(stroke
				(width 0.15)
				(type solid)
			)
			(layer "F.Fab")
		)
		(fp_line
			(start -0.494 0.248)
			(end -0.494 -0.25)
			(stroke
				(width 0.15)
				(type solid)
			)
			(layer "F.Fab")
		)
		(fp_line
			(start -0.494 -0.25)
			(end 0.504 -0.25)
			(stroke
				(width 0.15)
				(type solid)
			)
			(layer "F.Fab")
		)
		(fp_text user "License: Apache-2.0"
			(at -0.939 5.799 180)
			(layer "F.Fab")
			(effects
				(font
					(size 0.7 0.7)
					(thickness 0.15)
				)
				(justify left bottom)
			)
		)
		(fp_text user "Author: Antmicro"
			(at -0.939 3.399 180)
			(layer "F.Fab")
			(effects
				(font
					(size 0.7 0.7)
					(thickness 0.15)
				)
				(justify left bottom)
			)
		)
		(fp_text user "${REFERENCE}"
			(at -0.939 4.599 180)
			(layer "F.Fab")
			(effects
				(font
					(size 0.7 0.7)
					(thickness 0.15)
				)
				(justify left bottom)
			)
		)
		(pad "1" smd roundrect
			(at -0.48 0 180)
			(size 0.59 0.64)
			(layers "F.Cu" "F.Mask" "F.Paste")
			(roundrect_rratio 0.25)
			(net 251 "/SDI/SDI_OUT_F2")
			(pintype "passive")
		)
		(pad "2" smd roundrect
			(at 0.48 0 180)
			(size 0.59 0.64)
			(layers "F.Cu" "F.Mask" "F.Paste")
			(roundrect_rratio 0.25)
			(net 252 "/SDI/SDI_OUT")
			(pintype "passive")
		)
	)
	(footprint "antmicro-footprints:C_0402_1005Metric"
		(layer "F.Cu")
		(at 110.29 103.9 90)
		(descr "Capacitor SMD 0402")
		(tags "capacitor SMD 0402")
		(property "Reference" "C81"
			(at -1.14 2.44 90)
			(layer "F.SilkS")
			(effects
				(font
					(size 0.65 0.65)
					(thickness 0.15)
				)
				(justify left bottom)
			)
		)
		(property "Value" "C_100n_0402"
			(at 0 1.4 90)
			(layer "F.Fab")
			(hide yes)
			(effects
				(font
					(size 0.7 0.7)
					(thickness 0.15)
				)
				(justify left bottom)
			)
		)
		(property "Datasheet" "https://www.murata.com/products/productdetail?partno=GRM155R61H104KE14%23"
			(at 0 0 90)
			(layer "F.Fab")
			(hide yes)
			(effects
				(font
					(size 1.27 1.27)
					(thickness 0.15)
				)
			)
		)
		(property "Description" "SMD Multilayer Ceramic Capacitor, 0.1 µF, 50 V, 0402 [1005 Metric], ± 10%, X5R, GRM Series"
			(at 0 0 90)
			(layer "F.Fab")
			(hide yes)
			(effects
				(font
					(size 1.27 1.27)
					(thickness 0.15)
				)
			)
		)
		(property "Author" "Antmicro"
			(at 214.19 -6.39 0)
			(layer "F.Fab")
			(hide yes)
			(effects
				(font
					(size 1 1)
					(thickness 0.15)
				)
			)
		)
		(property "Dielectric" "X5R"
			(at 214.19 -6.39 0)
			(layer "F.Fab")
			(hide yes)
			(effects
				(font
					(size 1 1)
					(thickness 0.15)
				)
			)
		)
		(property "License" "Apache-2.0"
			(at 214.19 -6.39 0)
			(layer "F.Fab")
			(hide yes)
			(effects
				(font
					(size 1 1)
					(thickness 0.15)
				)
			)
		)
		(property "MPN" "GRM155R61H104KE14D"
			(at 214.19 -6.39 0)
			(layer "F.Fab")
			(hide yes)
			(effects
				(font
					(size 1 1)
					(thickness 0.15)
				)
			)
		)
		(property "Manufacturer" "Murata"
			(at 214.19 -6.39 0)
			(layer "F.Fab")
			(hide yes)
			(effects
				(font
					(size 1 1)
					(thickness 0.15)
				)
			)
		)
		(property "Val" "100n"
			(at 214.19 -6.39 0)
			(layer "F.Fab")
			(hide yes)
			(effects
				(font
					(size 1 1)
					(thickness 0.15)
				)
			)
		)
		(property "Voltage" "50V"
			(at 214.19 -6.39 0)
			(layer "F.Fab")
			(hide yes)
			(effects
				(font
					(size 1 1)
					(thickness 0.15)
				)
			)
		)
		(sheetname "/FPGA/")
		(sheetfile "fpga.kicad_sch")
		(attr smd)
		(fp_rect
			(start -0.925 -0.47)
			(end 0.925 0.47)
			(stroke
				(width 0.05)
				(type default)
			)
			(fill no)
			(layer "F.CrtYd")
		)
		(fp_line
			(start 0.504 -0.25)
			(end 0.504 0.248)
			(stroke
				(width 0.15)
				(type solid)
			)
			(layer "F.Fab")
		)
		(fp_line
			(start -0.494 -0.25)
			(end 0.504 -0.25)
			(stroke
				(width 0.15)
				(type solid)
			)
			(layer "F.Fab")
		)
		(fp_line
			(start 0.504 0.248)
			(end -0.494 0.248)
			(stroke
				(width 0.15)
				(type solid)
			)
			(layer "F.Fab")
		)
		(fp_line
			(start -0.494 0.248)
			(end -0.494 -0.25)
			(stroke
				(width 0.15)
				(type solid)
			)
			(layer "F.Fab")
		)
		(fp_text user "License: Apache-2.0"
			(at -0.939 5.799 90)
			(layer "F.Fab")
			(effects
				(font
					(size 0.7 0.7)
					(thickness 0.15)
				)
				(justify left bottom)
			)
		)
		(fp_text user "${REFERENCE}"
			(at -0.939 4.599 90)
			(layer "F.Fab")
			(effects
				(font
					(size 0.7 0.7)
					(thickness 0.15)
				)
				(justify left bottom)
			)
		)
		(fp_text user "Author: Antmicro"
			(at -0.939 3.399 90)
			(layer "F.Fab")
			(effects
				(font
					(size 0.7 0.7)
					(thickness 0.15)
				)
				(justify left bottom)
			)
		)
		(pad "1" smd roundrect
			(at -0.48 0 90)
			(size 0.59 0.64)
			(layers "F.Cu" "F.Mask" "F.Paste")
			(roundrect_rratio 0.25)
			(net 1 "GND")
			(pintype "passive")
		)
		(pad "2" smd roundrect
			(at 0.48 0 90)
			(size 0.59 0.64)
			(layers "F.Cu" "F.Mask" "F.Paste")
			(roundrect_rratio 0.25)
			(net 2 "+3V3")
			(pintype "passive")
		)
	)
	(footprint "antmicro-footprints:R_0603_1608Metric"
		(layer "F.Cu")
		(at 162.51 94.26 90)
		(descr "Resistor SMD 0603")
		(tags "resistor SMD 0603")
		(property "Reference" "R107"
			(at -1.34 -0.97 90)
			(layer "F.SilkS")
			(effects
				(font
					(size 0.65 0.65)
					(thickness 0.15)
				)
				(justify left bottom)
			)
		)
		(property "Value" "R_15k_0603"
			(at 0 1.6 90)
			(layer "F.Fab")
			(hide yes)
			(effects
				(font
					(size 0.7 0.7)
					(thickness 0.15)
				)
				(justify left bottom)
			)
		)
		(property "Datasheet" "https://www.bourns.com/docs/product-datasheets/cr.pdf"
			(at 0 0 90)
			(layer "F.Fab")
			(hide yes)
			(effects
				(font
					(size 1.27 1.27)
					(thickness 0.15)
				)
			)
		)
		(property "Description" "SMD Chip Resistor, 15 kohm, ± 1%, 100 mW, 0603 [1608 Metric], Thick Film, General Purpose"
			(at 0 0 90)
			(layer "F.Fab")
			(hide yes)
			(effects
				(font
					(size 1.27 1.27)
					(thickness 0.15)
				)
			)
		)
		(property "Author" "Antmicro"
			(at 256.8 -68.2 0)
			(layer "F.Fab")
			(hide yes)
			(effects
				(font
					(size 1 1)
					(thickness 0.15)
				)
			)
		)
		(property "License" "Apache-2.0"
			(at 256.8 -68.2 0)
			(layer "F.Fab")
			(hide yes)
			(effects
				(font
					(size 1 1)
					(thickness 0.15)
				)
			)
		)
		(property "MPN" "CR0603-FX-1502ELF"
			(at 256.8 -68.2 0)
			(layer "F.Fab")
			(hide yes)
			(effects
				(font
					(size 1 1)
					(thickness 0.15)
				)
			)
		)
		(property "Manufacturer" "Bourns"
			(at 256.8 -68.2 0)
			(layer "F.Fab")
			(hide yes)
			(effects
				(font
					(size 1 1)
					(thickness 0.15)
				)
			)
		)
		(property "Tolerance" "1%"
			(at 256.8 -68.2 0)
			(layer "F.Fab")
			(hide yes)
			(effects
				(font
					(size 1 1)
					(thickness 0.15)
				)
			)
		)
		(property "Val" "15k"
			(at 256.8 -68.2 0)
			(layer "F.Fab")
			(hide yes)
			(effects
				(font
					(size 1 1)
					(thickness 0.15)
				)
			)
		)
		(sheetname "/Peripherals/")
		(sheetfile "peripherals.kicad_sch")
		(attr smd)
		(fp_line
			(start -0.15 -0.4)
			(end 0.15 -0.4)
			(stroke
				(width 0.15)
				(type solid)
			)
			(layer "F.SilkS")
		)
		(fp_line
			(start -0.15 0.4)
			(end 0.15 0.4)
			(stroke
				(width 0.15)
				(type solid)
			)
			(layer "F.SilkS")
		)
		(fp_rect
			(start -1.25 -0.65)
			(end 1.25 0.65)
			(stroke
				(width 0.05)
				(type solid)
			)
			(fill no)
			(layer "F.CrtYd")
		)
		(fp_rect
			(start -0.8 -0.4)
			(end 0.8 0.4)
			(stroke
				(width 0.15)
				(type solid)
			)
			(fill no)
			(layer "F.Fab")
		)
		(fp_text user "License: Apache-2.0"
			(at -1.25 5.9 90)
			(layer "F.Fab")
			(effects
				(font
					(size 0.7 0.7)
					(thickness 0.15)
				)
				(justify left bottom)
			)
		)
		(fp_text user "${REFERENCE}"
			(at -1.25 3.898 90)
			(layer "F.Fab")
			(effects
				(font
					(size 0.7 0.7)
					(thickness 0.15)
				)
				(justify left bottom)
			)
		)
		(fp_text user "Author: Antmicro"
			(at -1.25 4.9 90)
			(layer "F.Fab")
			(effects
				(font
					(size 0.7 0.7)
					(thickness 0.15)
				)
				(justify left bottom)
			)
		)
		(pad "1" smd roundrect
			(at -0.7 0 90)
			(size 0.8 1)
			(layers "F.Cu" "F.Mask" "F.Paste")
			(roundrect_rratio 0.2)
			(net 1 "GND")
			(pintype "passive")
		)
		(pad "2" smd roundrect
			(at 0.7 0 90)
			(size 0.8 1)
			(layers "F.Cu" "F.Mask" "F.Paste")
			(roundrect_rratio 0.2)
			(net 353 "Net-(U13-ILIM)")
			(pintype "passive")
		)
	)
	(footprint "antmicro-footprints:LED_0603_1608Metric_G"
		(layer "F.Cu")
		(at 162.79 70.3 90)
		(descr "LED SMD 0603 Green")
		(tags "LED SMD 0603 Green")
		(property "Reference" "D2"
			(at 1.18 -0.09 90)
			(layer "F.SilkS")
			(effects
				(font
					(size 0.65 0.65)
					(thickness 0.15)
				)
				(justify left top)
			)
		)
		(property "Value" "LED_G_0603_LTST-C190GKT"
			(at 0 1.6 90)
			(layer "F.Fab")
			(hide yes)
			(effects
				(font
					(size 0.7 0.7)
					(thickness 0.15)
				)
				(justify left top)
			)
		)
		(property "Datasheet" "https://media.digikey.com/pdf/Data%20Sheets/Lite-On%20PDFs/LTST-C190GKT.pdf"
			(at 0 0 90)
			(layer "F.Fab")
			(hide yes)
			(effects
				(font
					(size 1.27 1.27)
					(thickness 0.15)
				)
			)
		)
		(property "Description" "LED, Green, SMD, 0603, 20 mA, 2.1 V, 569 nm"
			(at 0 0 90)
			(layer "F.Fab")
			(hide yes)
			(effects
				(font
					(size 1.27 1.27)
					(thickness 0.15)
				)
			)
		)
		(property "Author" "Antmicro"
			(at 92.49 233.09 0)
			(layer "F.Fab")
			(hide yes)
			(effects
				(font
					(size 1 1)
					(thickness 0.15)
				)
			)
		)
		(property "License" "Apache-2.0"
			(at 92.49 233.09 0)
			(layer "F.Fab")
			(hide yes)
			(effects
				(font
					(size 1 1)
					(thickness 0.15)
				)
			)
		)
		(property "MPN" "LTST-C190GKT"
			(at 92.49 233.09 0)
			(layer "F.Fab")
			(hide yes)
			(effects
				(font
					(size 1 1)
					(thickness 0.15)
				)
			)
		)
		(property "Manufacturer" "Lite-On"
			(at 92.49 233.09 0)
			(layer "F.Fab")
			(hide yes)
			(effects
				(font
					(size 1 1)
					(thickness 0.15)
				)
			)
		)
		(property "Color" "Green"
			(at 0 0 90)
			(unlocked yes)
			(layer "F.Fab")
			(hide yes)
			(effects
				(font
					(size 1 1)
					(thickness 0.15)
				)
			)
		)
		(sheetname "/Power Supply/")
		(sheetfile "supply.kicad_sch")
		(attr smd)
		(fp_line
			(start 0.22 -0.35)
			(end -0.22 -0.35)
			(stroke
				(width 0.15)
				(type solid)
			)
			(layer "F.SilkS")
		)
		(fp_line
			(start -1.18 -0.319)
			(end -1.18 0.321)
			(stroke
				(width 0.15)
				(type solid)
			)
			(layer "F.SilkS")
		)
		(fp_line
			(start 0.105328 0.001008)
			(end 0.24 0.001)
			(stroke
				(width 0.1)
				(type solid)
			)
			(layer "F.SilkS")
		)
		(fp_line
			(start -0.094672 0.001008)
			(end 0.105328 -0.198992)
			(stroke
				(width 0.1)
				(type solid)
			)
			(layer "F.SilkS")
		)
		(fp_line
			(start -0.094672 0.001008)
			(end -0.24 0.001008)
			(stroke
				(width 0.1)
				(type solid)
			)
			(layer "F.SilkS")
		)
		(fp_line
			(start 0.105328 0.201008)
			(end 0.105328 -0.198992)
			(stroke
				(width 0.1)
				(type solid)
			)
			(layer "F.SilkS")
		)
		(fp_line
			(start 0.105328 0.201008)
			(end -0.094672 0.001008)
			(stroke
				(width 0.1)
				(type solid)
			)
			(layer "F.SilkS")
		)
		(fp_line
			(start -0.094672 0.201008)
			(end -0.094672 -0.198992)
			(stroke
				(width 0.1)
				(type solid)
			)
			(layer "F.SilkS")
		)
		(fp_line
			(start 0.22 0.35)
			(end -0.22 0.35)
			(stroke
				(width 0.15)
				(type solid)
			)
			(layer "F.SilkS")
		)
		(fp_rect
			(start 1.25 0.65)
			(end -1.25 -0.65)
			(stroke
				(width 0.05)
				(type solid)
			)
			(fill no)
			(layer "F.CrtYd")
		)
		(fp_line
			(start 0.201 -0.202)
			(end -0.101 0)
			(stroke
				(width 0.15)
				(type solid)
			)
			(layer "F.Fab")
		)
		(fp_line
			(start -0.199 -0.202)
			(end -0.199 0.1)
			(stroke
				(width 0.15)
				(type solid)
			)
			(layer "F.Fab")
		)
		(fp_line
			(start 0.599 0)
			(end 0.201 0)
			(stroke
				(width 0.15)
				(type solid)
			)
			(layer "F.Fab")
		)
		(fp_line
			(start 0.201 0)
			(end 0.201 -0.202)
			(stroke
				(width 0.15)
				(type solid)
			)
			(layer "F.Fab")
		)
		(fp_line
			(start -0.101 0)
			(end 0.201 0.2)
			(stroke
				(width 0.15)
				(type solid)
			)
			(layer "F.Fab")
		)
		(fp_line
			(start -0.199 0)
			(end -0.597 0)
			(stroke
				(width 0.15)
				(type solid)
			)
			(layer "F.Fab")
		)
		(fp_line
			(start 0.201 0.2)
			(end 0.201 0)
			(stroke
				(width 0.15)
				(type solid)
			)
			(layer "F.Fab")
		)
		(fp_line
			(start -0.199 0.2)
			(end -0.199 0.1)
			(stroke
				(width 0.15)
				(type solid)
			)
			(layer "F.Fab")
		)
		(fp_rect
			(start 0.848 0.4)
			(end -0.85 -0.402)
			(stroke
				(width 0.15)
				(type solid)
			)
			(fill no)
			(layer "F.Fab")
		)
		(fp_text user "${REFERENCE}"
			(at -1.4224 5.999 90)
			(layer "F.Fab")
			(effects
				(font
					(size 0.7 0.7)
					(thickness 0.15)
				)
				(justify left bottom)
			)
		)
		(fp_text user "Author: Antmicro"
			(at -1.4224 4.799 90)
			(layer "F.Fab")
			(effects
				(font
					(size 0.7 0.7)
					(thickness 0.15)
				)
				(justify left bottom)
			)
		)
		(fp_text user "License: Apache-2.0"
			(at -1.4224 3.599 90)
			(layer "F.Fab")
			(effects
				(font
					(size 0.7 0.7)
					(thickness 0.15)
				)
				(justify left bottom)
			)
		)
		(pad "1" smd roundrect
			(at -0.7 0 270)
			(size 0.8 1)
			(layers "F.Cu" "F.Mask" "F.Paste")
			(roundrect_rratio 0.2)
			(net 1 "GND")
			(pinfunction "C")
			(pintype "passive")
		)
		(pad "2" smd roundrect
			(at 0.7 0 270)
			(size 0.8 1)
			(layers "F.Cu" "F.Mask" "F.Paste")
			(roundrect_rratio 0.2)
			(net 62 "Net-(D2-A)")
			(pinfunction "A")
			(pintype "passive")
		)
	)
)
